# BASEBOARD_FAB2 (Tioga Pass) — schematic netlist excerpt (pin names and nets, part order shuffled) for the footprints in the layout excerpt that follows; sources: Cadence DE-HDL packaged netlist, KiCad conversion of Wiwynn_Tioga_Pass_MB.brd

R3F2  RES  0.0 5% CHIP  pkg 0402  page 104 : A = CLK_156M_OSC_BRD_CPU1_DN ; B = CLK_156M_OSC_CPU1_HFI_DN
C4G20  CAP  22UF 4V 20% X6S  pkg 0805LF  page 229 : A = PVTT_GHJ ; B = GND
R8A1  RES  10.0 1% CHIP  pkg 0402  page 235 : A = VSENSE_PVNN_PCH_STBY_AVSP ; B = VR_PVNN_PCH_AVSP

(kicad_pcb
	(version 20260206)
	(generator "pcbnew")
	(generator_version "10.0")
	(general
		(thickness 1.6)
		(legacy_teardrops no)
	)
	(paper "A4")
	(title_block
		(title "Wiwynn_Tioga_Pass_MB.brd")
		(comment 1 "Tioga Pass / footprints 44-46 of 4770")
	)
	(layers
		(0 "F.Cu" signal "TOP")
		(4 "In1.Cu" signal "L2GND")
		(6 "In2.Cu" signal "L3")
		(8 "In3.Cu" signal "L4GND")
		(10 "In4.Cu" signal "L5")
		(12 "In5.Cu" signal "L6GND")
		(14 "In6.Cu" signal "L7VCC")
		(16 "In7.Cu" signal "L8VCC")
		(18 "In8.Cu" signal "L9GND")
		(20 "In9.Cu" signal "L10")
		(22 "In10.Cu" signal "L11GND")
		(24 "In11.Cu" signal "L12")
		(26 "In12.Cu" signal "L13GND")
		(2 "B.Cu" signal "BOTTOM")
		(9 "F.Adhes" user "F.Adhesive")
		(11 "B.Adhes" user "B.Adhesive")
		(13 "F.Paste" user "Package Geometry/Pastemask Top")
		(15 "B.Paste" user "Package Geometry/Pastemask Bottom")
		(5 "F.SilkS" user "Ref Des/Silkscreen Top")
		(7 "B.SilkS" user "Ref Des/Silkscreen Bottom")
		(1 "F.Mask" user "Board Geometry/Soldermask Top")
		(3 "B.Mask" user "Board Geometry/Soldermask Bottom")
		(17 "Dwgs.User" user "User.Drawings")
		(19 "Cmts.User" user "User.Comments")
		(21 "Eco1.User" user "User.Eco1")
		(23 "Eco2.User" user "User.Eco2")
		(25 "Edge.Cuts" user "Board Geometry/Outline")
		(27 "Margin" user)
		(31 "F.CrtYd" user "Package Geometry/Place Bound Top")
		(29 "B.CrtYd" user "Package Geometry/Place Bound Bottom")
		(35 "F.Fab" user "Ref Des/Assembly Top")
		(33 "B.Fab" user "Ref Des/Assembly Bottom")
	)
	(footprint ""
		(layer "F.Cu")
		(at 400.558 -156.718)
		(property "Reference" "R8A1"
			(at 0 0 0)
			(layer "F.SilkS")
			(hide yes)
			(effects
				(font
					(size 1.27 1.27)
				)
			)
		)
		(property "Value" ""
			(at 0 0 0)
			(layer "F.Fab")
			(effects
				(font
					(size 1.27 1.27)
				)
			)
		)
		(duplicate_pad_numbers_are_jumpers no)
		(fp_poly
			(pts
				(xy -0.2794 -0.1016) (xy 0.2794 -0.1016) (xy 0.2794 0.9906) (xy -0.2794 0.9906)
			)
			(stroke
				(width 0)
				(type default)
			)
			(fill no)
			(layer "F.CrtYd")
		)
		(fp_line
			(start -0.2794 -0.1016)
			(end -0.2794 0.9906)
			(stroke
				(width 0.1)
				(type default)
			)
			(layer "F.Fab")
		)
		(fp_line
			(start -0.2794 0.9906)
			(end 0.2794 0.9906)
			(stroke
				(width 0.1)
				(type default)
			)
			(layer "F.Fab")
		)
		(fp_line
			(start 0.2794 -0.1016)
			(end -0.2794 -0.1016)
			(stroke
				(width 0.1)
				(type default)
			)
			(layer "F.Fab")
		)
		(fp_line
			(start 0.2794 0.9906)
			(end 0.2794 -0.1016)
			(stroke
				(width 0.1)
				(type default)
			)
			(layer "F.Fab")
		)
		(pad "1" smd rect
			(at 0 0)
			(size 0.508 0.508)
			(layers "F.Cu" "F.Mask" "F.Paste")
			(net "VSENSE_PVNN_PCH_STBY_AVSP")
		)
		(pad "2" smd rect
			(at 0 0.889)
			(size 0.508 0.508)
			(layers "F.Cu" "F.Mask" "F.Paste")
			(net "VR_PVNN_PCH_AVSP")
		)
		(zone
			(layer "F.Cu")
			(hatch none 0.5)
			(connect_pads
				(clearance 0)
			)
			(min_thickness 0.25)
			(keepout
				(tracks allowed)
				(vias not_allowed)
				(pads allowed)
				(copperpour not_allowed)
				(footprints allowed)
			)
			(placement
				(enabled no)
				(sheetname "")
			)
			(fill
				(thermal_gap 0.5)
				(thermal_bridge_width 0.5)
				(island_removal_mode 0)
			)
			(polygon
				(pts
					(xy 400.304 -156.464) (xy 400.812 -156.464) (xy 400.812 -156.083) (xy 400.304 -156.083)
				)
			)
		)
		(zone
			(layer "F.Cu")
			(hatch none 0.5)
			(connect_pads
				(clearance 0)
			)
			(min_thickness 0.25)
			(keepout
				(tracks not_allowed)
				(vias allowed)
				(pads allowed)
				(copperpour not_allowed)
				(footprints allowed)
			)
			(placement
				(enabled no)
				(sheetname "")
			)
			(fill
				(thermal_gap 0.5)
				(thermal_bridge_width 0.5)
				(island_removal_mode 0)
			)
			(polygon
				(pts
					(xy 400.304 -156.083) (xy 400.812 -156.083) (xy 400.812 -156.464) (xy 400.304 -156.464)
				)
			)
		)
	)
	(footprint ""
		(layer "F.Cu")
		(at 154.305 -29.6418 90)
		(property "Reference" "R3F2"
			(at 0 0 90)
			(layer "F.SilkS")
			(hide yes)
			(effects
				(font
					(size 1.27 1.27)
				)
			)
		)
		(property "Value" ""
			(at 0 0 90)
			(layer "F.Fab")
			(effects
				(font
					(size 1.27 1.27)
				)
			)
		)
		(duplicate_pad_numbers_are_jumpers no)
		(fp_poly
			(pts
				(xy -0.2794 -0.1016) (xy 0.2794 -0.1016) (xy 0.2794 0.9906) (xy -0.2794 0.9906)
			)
			(stroke
				(width 0)
				(type default)
			)
			(fill no)
			(layer "F.CrtYd")
		)
		(fp_line
			(start 0.2794 -0.1016)
			(end -0.2794 -0.1016)
			(stroke
				(width 0.1)
				(type default)
			)
			(layer "F.Fab")
		)
		(fp_line
			(start -0.2794 -0.1016)
			(end -0.2794 0.9906)
			(stroke
				(width 0.1)
				(type default)
			)
			(layer "F.Fab")
		)
		(fp_line
			(start 0.2794 0.9906)
			(end 0.2794 -0.1016)
			(stroke
				(width 0.1)
				(type default)
			)
			(layer "F.Fab")
		)
		(fp_line
			(start -0.2794 0.9906)
			(end 0.2794 0.9906)
			(stroke
				(width 0.1)
				(type default)
			)
			(layer "F.Fab")
		)
		(pad "1" smd rect
			(at 0 0 90)
			(size 0.508 0.508)
			(layers "F.Cu" "F.Mask" "F.Paste")
			(net "CLK_156M_OSC_BRD_CPU1_DN")
		)
		(pad "2" smd rect
			(at 0 0.889 90)
			(size 0.508 0.508)
			(layers "F.Cu" "F.Mask" "F.Paste")
			(net "CLK_156M_OSC_CPU1_HFI_DN")
		)
		(zone
			(layer "F.Cu")
			(hatch none 0.5)
			(connect_pads
				(clearance 0)
			)
			(min_thickness 0.25)
			(keepout
				(tracks allowed)
				(vias not_allowed)
				(pads allowed)
				(copperpour not_allowed)
				(footprints allowed)
			)
			(placement
				(enabled no)
				(sheetname "")
			)
			(fill
				(thermal_gap 0.5)
				(thermal_bridge_width 0.5)
				(island_removal_mode 0)
			)
			(polygon
				(pts
					(xy 154.559 -29.3878) (xy 154.559 -29.8958) (xy 154.94 -29.8958) (xy 154.94 -29.3878)
				)
			)
		)
		(zone
			(layer "F.Cu")
			(hatch none 0.5)
			(connect_pads
				(clearance 0)
			)
			(min_thickness 0.25)
			(keepout
				(tracks not_allowed)
				(vias allowed)
				(pads allowed)
				(copperpour not_allowed)
				(footprints allowed)
			)
			(placement
				(enabled no)
				(sheetname "")
			)
			(fill
				(thermal_gap 0.5)
				(thermal_bridge_width 0.5)
				(island_removal_mode 0)
			)
			(polygon
				(pts
					(xy 154.94 -29.3878) (xy 154.94 -29.8958) (xy 154.559 -29.8958) (xy 154.559 -29.3878)
				)
			)
		)
	)
	(footprint ""
		(layer "F.Cu")
		(at 166.497 -3.048 180)
		(property "Reference" "C4G20"
			(at 0 0 180)
			(layer "F.SilkS")
			(hide yes)
			(effects
				(font
					(size 1.27 1.27)
				)
			)
		)
		(property "Value" ""
			(at 0 0 180)
			(layer "F.Fab")
			(effects
				(font
					(size 1.27 1.27)
				)
			)
		)
		(duplicate_pad_numbers_are_jumpers no)
		(fp_rect
			(start -0.7239 1.9939)
			(end 0.7239 -0.2159)
			(stroke
				(width 0)
				(type default)
			)
			(fill no)
			(layer "F.CrtYd")
		)
		(fp_line
			(start 0.7239 1.9939)
			(end 0.7239 -0.2159)
			(stroke
				(width 0.1)
				(type default)
			)
			(layer "F.Fab")
		)
		(fp_line
			(start 0.7239 -0.2159)
			(end -0.7239 -0.2159)
			(stroke
				(width 0.1)
				(type default)
			)
			(layer "F.Fab")
		)
		(fp_line
			(start -0.7239 1.9939)
			(end 0.7239 1.9939)
			(stroke
				(width 0.1)
				(type default)
			)
			(layer "F.Fab")
		)
		(fp_line
			(start -0.7239 -0.2159)
			(end -0.7239 1.9939)
			(stroke
				(width 0.1)
				(type default)
			)
			(layer "F.Fab")
		)
		(pad "1" smd rect
			(at 0 0 180)
			(size 1.27 1.016)
			(layers "F.Cu" "F.Mask" "F.Paste")
			(net "PVTT_GHJ")
		)
		(pad "2" smd rect
			(at 0 1.778 180)
			(size 1.27 1.016)
			(layers "F.Cu" "F.Mask" "F.Paste")
			(net "GND")
		)
		(zone
			(layer "F.Cu")
			(hatch none 0.5)
			(connect_pads
				(clearance 0)
			)
			(min_thickness 0.25)
			(keepout
				(tracks not_allowed)
				(vias allowed)
				(pads allowed)
				(copperpour not_allowed)
				(footprints allowed)
			)
			(placement
				(enabled no)
				(sheetname "")
			)
			(fill
				(thermal_gap 0.5)
				(thermal_bridge_width 0.5)
				(island_removal_mode 0)
			)
			(polygon
				(pts
					(xy 167.132 -4.318) (xy 165.862 -4.318) (xy 165.862 -3.556) (xy 167.132 -3.556)
				)
			)
		)
	)
)
